# S9S_MB_2U (Grand Teton) — schematic netlist excerpt (pin names and nets, part order shuffled) for the footprints in the layout excerpt that follows; sources: Cadence DE-HDL packaged netlist, KiCad conversion of 03242023_DA0F0TMBIJ0_F0T_Motherboard_J_brd_V01_OCP.brd

PC243_P0_7  Q_CAP  1UF 16V 10% X6S  pkg C0402  page 270 : A = PVCCIN_CPU0 ; B = GND
PR305  Q_RES  0 5% CHIP  pkg 0402LF  page 284 : A = PVCCIN_CPU1_CSPIN ; B = GND

(kicad_pcb
	(version 20260206)
	(generator "pcbnew")
	(generator_version "10.0")
	(general
		(thickness 1.6)
		(legacy_teardrops no)
	)
	(paper "A4")
	(title_block
		(title "03242023_DA0F0TMBIJ0_F0T_Motherboard_J_brd_V01_OCP.brd")
		(comment 1 "Grand Teton / footprints 5021-5022 of 6105")
	)
	(layers
		(0 "F.Cu" signal "TOP")
		(4 "In1.Cu" signal "GND")
		(6 "In2.Cu" signal "IN1")
		(8 "In3.Cu" signal "GND1")
		(10 "In4.Cu" signal "IN2")
		(12 "In5.Cu" signal "GND2")
		(14 "In6.Cu" signal "IN3")
		(16 "In7.Cu" signal "GND3")
		(18 "In8.Cu" signal "VCC")
		(20 "In9.Cu" signal "VCC1")
		(22 "In10.Cu" signal "GND4")
		(24 "In11.Cu" signal "IN4")
		(26 "In12.Cu" signal "GND5")
		(28 "In13.Cu" signal "IN5")
		(30 "In14.Cu" signal "GND6")
		(32 "In15.Cu" signal "IN6")
		(34 "In16.Cu" signal "GND7")
		(2 "B.Cu" signal "BOTTOM")
		(9 "F.Adhes" user "F.Adhesive")
		(11 "B.Adhes" user "B.Adhesive")
		(13 "F.Paste" user "Package Geometry/Pastemask Top")
		(15 "B.Paste" user "Package Geometry/Pastemask Bottom")
		(5 "F.SilkS" user "Ref Des/Silkscreen Top")
		(7 "B.SilkS" user "Ref Des/Silkscreen Bottom")
		(1 "F.Mask" user "Board Geometry/Soldermask Top")
		(3 "B.Mask" user "Board Geometry/Soldermask Bottom")
		(17 "Dwgs.User" user "User.Drawings")
		(19 "Cmts.User" user "User.Comments")
		(21 "Eco1.User" user "User.Eco1")
		(23 "Eco2.User" user "User.Eco2")
		(25 "Edge.Cuts" user "Board Geometry/Outline")
		(27 "Margin" user)
		(31 "F.CrtYd" user "Package Geometry/Place Bound Top")
		(29 "B.CrtYd" user "Package Geometry/Place Bound Bottom")
		(35 "F.Fab" user "Ref Des/Assembly Top")
		(33 "B.Fab" user "Ref Des/Assembly Bottom")
	)
	(footprint ""
		(layer "B.Cu")
		(at 110.866936 -359.47985)
		(property "Reference" "PR305"
			(at 0 0 0)
			(layer "B.SilkS")
			(hide yes)
			(effects
				(font
					(size 1.27 1.27)
				)
				(justify mirror)
			)
		)
		(property "Value" ""
			(at 0 0 0)
			(layer "B.Fab")
			(effects
				(font
					(size 1.27 1.27)
				)
				(justify mirror)
			)
		)
		(duplicate_pad_numbers_are_jumpers no)
		(fp_line
			(start -0.7874 -0.4064)
			(end -0.7874 0.4064)
			(stroke
				(width 0.1524)
				(type default)
			)
			(layer "B.SilkS")
		)
		(fp_line
			(start -0.7874 0.4064)
			(end 0.7874 0.4064)
			(stroke
				(width 0.1524)
				(type default)
			)
			(layer "B.SilkS")
		)
		(fp_line
			(start 0.7874 -0.4064)
			(end -0.7874 -0.4064)
			(stroke
				(width 0.1524)
				(type default)
			)
			(layer "B.SilkS")
		)
		(fp_line
			(start 0.7874 0.4064)
			(end 0.7874 -0.4064)
			(stroke
				(width 0.1524)
				(type default)
			)
			(layer "B.SilkS")
		)
		(fp_line
			(start -0.67945 -0.3048)
			(end -0.67945 0.3048)
			(stroke
				(width 0.1)
				(type default)
			)
			(layer "B.Fab")
		)
		(fp_line
			(start -0.67945 0.3048)
			(end -0.120396 0.3048)
			(stroke
				(width 0.1)
				(type default)
			)
			(layer "B.Fab")
		)
		(fp_line
			(start -0.12065 -0.3048)
			(end -0.67945 -0.3048)
			(stroke
				(width 0.1)
				(type default)
			)
			(layer "B.Fab")
		)
		(fp_line
			(start -0.12065 -0.2794)
			(end -0.12065 -0.3048)
			(stroke
				(width 0.1)
				(type default)
			)
			(layer "B.Fab")
		)
		(fp_line
			(start -0.120396 0.2794)
			(end 0.12065 0.2794)
			(stroke
				(width 0.1)
				(type default)
			)
			(layer "B.Fab")
		)
		(fp_line
			(start -0.120396 0.3048)
			(end -0.120396 0.2794)
			(stroke
				(width 0.1)
				(type default)
			)
			(layer "B.Fab")
		)
		(fp_line
			(start 0.12065 -0.305054)
			(end 0.12065 -0.2794)
			(stroke
				(width 0.1)
				(type default)
			)
			(layer "B.Fab")
		)
		(fp_line
			(start 0.12065 -0.2794)
			(end -0.12065 -0.2794)
			(stroke
				(width 0.1)
				(type default)
			)
			(layer "B.Fab")
		)
		(fp_line
			(start 0.12065 0.2794)
			(end 0.12065 0.3048)
			(stroke
				(width 0.1)
				(type default)
			)
			(layer "B.Fab")
		)
		(fp_line
			(start 0.12065 0.3048)
			(end 0.67945 0.3048)
			(stroke
				(width 0.1)
				(type default)
			)
			(layer "B.Fab")
		)
		(fp_line
			(start 0.67945 -0.305054)
			(end 0.12065 -0.305054)
			(stroke
				(width 0.1)
				(type default)
			)
			(layer "B.Fab")
		)
		(fp_line
			(start 0.67945 0.3048)
			(end 0.67945 -0.305054)
			(stroke
				(width 0.1)
				(type default)
			)
			(layer "B.Fab")
		)
		(pad "1" smd circle
			(at 0.40005 0 180)
			(size 0 0)
			(layers "B.Cu" "B.Mask" "B.Paste")
			(net "PVCCIN_CPU1_CSPIN")
		)
		(pad "2" smd circle
			(at -0.40005 0 180)
			(size 0 0)
			(layers "B.Cu" "B.Mask" "B.Paste")
			(net "GND")
		)
	)
	(footprint ""
		(layer "B.Cu")
		(at 331.155294 -333.896208 -90)
		(property "Reference" "PC243_P0_7"
			(at 0 0 90)
			(layer "B.SilkS")
			(hide yes)
			(effects
				(font
					(size 1.27 1.27)
				)
				(justify mirror)
			)
		)
		(property "Value" ""
			(at 0 0 90)
			(layer "B.Fab")
			(effects
				(font
					(size 1.27 1.27)
				)
				(justify mirror)
			)
		)
		(duplicate_pad_numbers_are_jumpers no)
		(fp_line
			(start -0.7874 0.4064)
			(end 0.7874 0.4064)
			(stroke
				(width 0.1524)
				(type default)
			)
			(layer "B.SilkS")
		)
		(fp_line
			(start 0.7874 0.4064)
			(end 0.7874 -0.4064)
			(stroke
				(width 0.1524)
				(type default)
			)
			(layer "B.SilkS")
		)
		(fp_line
			(start -0.7874 -0.4064)
			(end -0.7874 0.4064)
			(stroke
				(width 0.1524)
				(type default)
			)
			(layer "B.SilkS")
		)
		(fp_line
			(start 0.7874 -0.4064)
			(end -0.7874 -0.4064)
			(stroke
				(width 0.1524)
				(type default)
			)
			(layer "B.SilkS")
		)
		(fp_line
			(start -0.67945 0.3048)
			(end -0.120396 0.3048)
			(stroke
				(width 0.1)
				(type default)
			)
			(layer "B.Fab")
		)
		(fp_line
			(start -0.120396 0.3048)
			(end -0.120396 0.2794)
			(stroke
				(width 0.1)
				(type default)
			)
			(layer "B.Fab")
		)
		(fp_line
			(start 0.12065 0.3048)
			(end 0.67945 0.3048)
			(stroke
				(width 0.1)
				(type default)
			)
			(layer "B.Fab")
		)
		(fp_line
			(start 0.67945 0.3048)
			(end 0.67945 -0.305054)
			(stroke
				(width 0.1)
				(type default)
			)
			(layer "B.Fab")
		)
		(fp_line
			(start -0.120396 0.2794)
			(end 0.12065 0.2794)
			(stroke
				(width 0.1)
				(type default)
			)
			(layer "B.Fab")
		)
		(fp_line
			(start 0.12065 0.2794)
			(end 0.12065 0.3048)
			(stroke
				(width 0.1)
				(type default)
			)
			(layer "B.Fab")
		)
		(fp_line
			(start -0.12065 -0.2794)
			(end -0.12065 -0.3048)
			(stroke
				(width 0.1)
				(type default)
			)
			(layer "B.Fab")
		)
		(fp_line
			(start 0.12065 -0.2794)
			(end -0.12065 -0.2794)
			(stroke
				(width 0.1)
				(type default)
			)
			(layer "B.Fab")
		)
		(fp_line
			(start -0.67945 -0.3048)
			(end -0.67945 0.3048)
			(stroke
				(width 0.1)
				(type default)
			)
			(layer "B.Fab")
		)
		(fp_line
			(start -0.12065 -0.3048)
			(end -0.67945 -0.3048)
			(stroke
				(width 0.1)
				(type default)
			)
			(layer "B.Fab")
		)
		(fp_line
			(start 0.12065 -0.305054)
			(end 0.12065 -0.2794)
			(stroke
				(width 0.1)
				(type default)
			)
			(layer "B.Fab")
		)
		(fp_line
			(start 0.67945 -0.305054)
			(end 0.12065 -0.305054)
			(stroke
				(width 0.1)
				(type default)
			)
			(layer "B.Fab")
		)
		(pad "1" smd circle
			(at 0.40005 0 90)
			(size 0 0)
			(layers "B.Cu" "B.Mask" "B.Paste")
			(net "PVCCIN_CPU0")
		)
		(pad "2" smd circle
			(at -0.40005 0 90)
			(size 0 0)
			(layers "B.Cu" "B.Mask" "B.Paste")
			(net "GND")
		)
	)
)
